(kicad_pcb
	(version 20221018)
	(generator pcbnew)
	(general
    (thickness 1.562)
  )
	(paper "A4")
	(title_block
    (title "Thunderbolt PCIe Adaper")
    (date "2024-07-09")
    (rev "1.0.3")
    (comment 1 "www.antmicro.com")
    (comment 2 "Antmicro Ltd.")
		(comment 9 "footprints 236-244 of 271")
	)
	(layers
    (0 "F.Cu" signal)
    (1 "In1.Cu" signal)
    (2 "In2.Cu" signal)
    (3 "In3.Cu" signal)
    (4 "In4.Cu" signal)
    (31 "B.Cu" signal)
    (32 "B.Adhes" user "B.Adhesive")
    (33 "F.Adhes" user "F.Adhesive")
    (34 "B.Paste" user)
    (35 "F.Paste" user)
    (36 "B.SilkS" user "B.Silkscreen")
    (37 "F.SilkS" user "F.Silkscreen")
    (38 "B.Mask" user)
    (39 "F.Mask" user)
    (40 "Dwgs.User" user "User.Drawings")
    (41 "Cmts.User" user "User.Comments")
    (42 "Eco1.User" user "User.Eco1")
    (43 "Eco2.User" user "User.Eco2")
    (44 "Edge.Cuts" user)
    (45 "Margin" user)
    (46 "B.CrtYd" user "B.Courtyard")
    (47 "F.CrtYd" user "F.Courtyard")
    (48 "B.Fab" user)
    (49 "F.Fab" user)
  )
	(footprint "antmicro-footprints:C_0402_1005Metric" (layer "B.Cu")
    (at 111.725 79.65)
    (descr "Capacitor SMD 0402")
    (tags "capacitor SMD 0402")
    (property "Author" "Antmicro")
    (property "Dielectric" "X5R")
    (property "License" "Apache-2.0")
    (property "MPN" "GRM155R61H104KE14D")
    (property "Manufacturer" "Murata")
    (property "Sheetfile" "power.kicad_sch")
    (property "Sheetname" "Power")
    (property "Val" "100n")
    (property "Voltage" "50V")
    (property "ki_description" "SMD Multilayer Ceramic Capacitor, 0.1 µF, 50 V, 0402 [1005 Metric], ± 10%, X5R, GRM Series")
    (property "ki_keywords" "0402, SMT, CAPACITOR, PASSIVE, CERAMIC, MLCC")
    (attr smd)
    (fp_text reference "C28" (at 1.051 -4.72 180) (layer "B.SilkS")
        (effects (font (size 0.7 0.7) (thickness 0.15)) (justify left bottom mirror))
    )
    (fp_text value "C_100n_0402" (at -1.022927 -2.155213 180) (layer "B.Fab")
        (effects (font (size 0.7 0.7) (thickness 0.15)) (justify left bottom mirror))
    )
    (fp_text user "${REFERENCE}" (at -0.939 -4.599 180) (layer "B.Fab") hide
        (effects (font (size 0.7 0.7) (thickness 0.15)) (justify left bottom mirror))
    )
    (fp_text user "Author: Antmicro" (at -0.939 -3.399 180) (layer "B.Fab") hide
        (effects (font (size 0.7 0.7) (thickness 0.15)) (justify left bottom mirror))
    )
    (fp_text user "License: Apache-2.0" (at -0.939 -5.799 180) (layer "B.Fab") hide
        (effects (font (size 0.7 0.7) (thickness 0.15)) (justify left bottom mirror))
    )
    (fp_rect (start -0.925 0.47) (end 0.925 -0.47)
      (stroke (width 0.05) (type default)) (fill none) (layer "B.CrtYd"))
    (fp_line (start -0.494 -0.248) (end -0.494 0.25)
      (stroke (width 0.15) (type solid)) (layer "B.Fab"))
    (fp_line (start -0.494 0.25) (end 0.504 0.25)
      (stroke (width 0.15) (type solid)) (layer "B.Fab"))
    (fp_line (start 0.504 -0.248) (end -0.494 -0.248)
      (stroke (width 0.15) (type solid)) (layer "B.Fab"))
    (fp_line (start 0.504 0.25) (end 0.504 -0.248)
      (stroke (width 0.15) (type solid)) (layer "B.Fab"))
    (pad "1" smd roundrect (at -0.48 0) (size 0.59 0.64) (layers "B.Cu" "B.Paste" "B.Mask") (roundrect_rratio 0.25)
      (net 96 "Net-(U1-BST2)") (pintype "passive"))
    (pad "2" smd roundrect (at 0.48 0) (size 0.59 0.64) (layers "B.Cu" "B.Paste" "B.Mask") (roundrect_rratio 0.25)
      (net 268 "Net-(C28-Pad2)") (pintype "passive"))
  )
	(footprint "antmicro-footprints:C_0805_2012Metric" (layer "B.Cu")
    (at 114.8 93.55 180)
    (descr "Capacitor SMD 0805")
    (tags "capacitor SMD 0805")
    (property "Author" "Antmicro")
    (property "Dielectric" "")
    (property "License" "Apache-2.0")
    (property "MPN" "GRM21BR6YA106KE43L")
    (property "Manufacturer" "Murata")
    (property "Sheetfile" "connectors.kicad_sch")
    (property "Sheetname" "Connectors")
    (property "Val" "10u")
    (property "Voltage" "35V")
    (property "ki_description" "SMD Multilayer Ceramic Capacitor, 10 µF, 35 V, 0805 [2012 Metric], ± 10%, X5R, GRM Series")
    (property "ki_keywords" "0805, SMT, CAPACITOR, PASSIVE")
    (attr smd)
    (fp_text reference "C6" (at -3.564 -0.43) (layer "B.SilkS")
        (effects (font (size 0.7 0.7) (thickness 0.15)) (justify left bottom mirror))
    )
    (fp_text value "C_10u_0805_35V" (at -2.055717 -1.963152) (layer "B.Fab")
        (effects (font (size 0.7 0.7) (thickness 0.15)) (justify left bottom mirror))
    )
    (fp_text user "${REFERENCE}" (at -1.9 -3.947) (layer "B.Fab") hide
        (effects (font (size 0.7 0.7) (thickness 0.15)) (justify left bottom mirror))
    )
    (fp_text user "License: Apache-2.0" (at -1.9 -4.947) (layer "B.Fab") hide
        (effects (font (size 0.7 0.7) (thickness 0.15)) (justify left bottom mirror))
    )
    (fp_text user "Author: Antmicro" (at -1.9 -5.947) (layer "B.Fab") hide
        (effects (font (size 0.7 0.7) (thickness 0.15)) (justify left bottom mirror))
    )
    (fp_line (start -0.3 -0.7) (end 0.3 -0.7)
      (stroke (width 0.15) (type solid)) (layer "B.SilkS"))
    (fp_line (start -0.3 0.7) (end 0.3 0.7)
      (stroke (width 0.15) (type solid)) (layer "B.SilkS"))
    (fp_rect (start 1.95 0.9) (end -1.95 -0.9)
      (stroke (width 0.05) (type default)) (fill none) (layer "B.CrtYd"))
    (fp_rect (start -0.95 0.675) (end 0.95 -0.675)
      (stroke (width 0.15) (type solid)) (fill none) (layer "B.Fab"))
    (pad "1" smd roundrect (at -1.1 0 180) (size 1.2 1.3) (layers "B.Cu" "B.Paste" "B.Mask") (roundrect_rratio 0.25)
      (net 1 "GND") (pintype "passive"))
    (pad "2" smd roundrect (at 1.1 0 180) (size 1.2 1.3) (layers "B.Cu" "B.Paste" "B.Mask") (roundrect_rratio 0.25)
      (net 8 "12V0_PCIE") (pintype "passive"))
  )
	(footprint "antmicro-footprints:C_0402_1005Metric" (layer "B.Cu")
    (at 153.41 63.97)
    (descr "Capacitor SMD 0402")
    (tags "capacitor SMD 0402")
    (property "Author" "Antmicro")
    (property "Dielectric" "")
    (property "License" "Apache-2.0")
    (property "MPN" "CC0402MRX5R5BB106")
    (property "Manufacturer" "YAGEO")
    (property "Sheetfile" "power.kicad_sch")
    (property "Sheetname" "Power")
    (property "Val" "10u")
    (property "Voltage" "")
    (property "ki_description" "SMD Multilayer Ceramic Capacitor, 10 µF, 6.3 V, 0402 [1005 Metric], ± 20%, X5R, CC Series")
    (property "ki_keywords" "0402, SMT, CAPACITOR, PASSIVE, MLCC, CERAMIC")
    (attr smd)
    (fp_text reference "C23" (at 0.768 4.483 180) (layer "B.SilkS")
        (effects (font (size 0.7 0.7) (thickness 0.15)) (justify left bottom mirror))
    )
    (fp_text value "C_10u_0402" (at -1.022927 -2.155213 180) (layer "B.Fab")
        (effects (font (size 0.7 0.7) (thickness 0.15)) (justify left bottom mirror))
    )
    (fp_text user "Author: Antmicro" (at -0.939 -3.399 180) (layer "B.Fab") hide
        (effects (font (size 0.7 0.7) (thickness 0.15)) (justify left bottom mirror))
    )
    (fp_text user "${REFERENCE}" (at -0.939 -4.599 180) (layer "B.Fab") hide
        (effects (font (size 0.7 0.7) (thickness 0.15)) (justify left bottom mirror))
    )
    (fp_text user "License: Apache-2.0" (at -0.939 -5.799 180) (layer "B.Fab") hide
        (effects (font (size 0.7 0.7) (thickness 0.15)) (justify left bottom mirror))
    )
    (fp_rect (start -0.925 0.47) (end 0.925 -0.47)
      (stroke (width 0.05) (type default)) (fill none) (layer "B.CrtYd"))
    (fp_line (start -0.494 -0.248) (end -0.494 0.25)
      (stroke (width 0.15) (type solid)) (layer "B.Fab"))
    (fp_line (start -0.494 0.25) (end 0.504 0.25)
      (stroke (width 0.15) (type solid)) (layer "B.Fab"))
    (fp_line (start 0.504 -0.248) (end -0.494 -0.248)
      (stroke (width 0.15) (type solid)) (layer "B.Fab"))
    (fp_line (start 0.504 0.25) (end 0.504 -0.248)
      (stroke (width 0.15) (type solid)) (layer "B.Fab"))
    (pad "1" smd roundrect (at -0.48 0) (size 0.59 0.64) (layers "B.Cu" "B.Paste" "B.Mask") (roundrect_rratio 0.25)
      (net 1 "GND") (pintype "passive"))
    (pad "2" smd roundrect (at 0.48 0) (size 0.59 0.64) (layers "B.Cu" "B.Paste" "B.Mask") (roundrect_rratio 0.25)
      (net 2 "3V3_SYS") (pintype "passive"))
  )
	(footprint "antmicro-footprints:R_0402_1005Metric" (layer "B.Cu")
    (at 161.41 60.97)
    (descr "Resistor SMD 0402")
    (tags "resistor SMD 0402")
    (property "Author" "Antmicro")
    (property "License" "Apache-2.0")
    (property "MPN" "CR0402-FX-1003GLF")
    (property "Manufacturer" "Bourns")
    (property "Sheetfile" "power.kicad_sch")
    (property "Sheetname" "Power")
    (property "Tolerance" "1%")
    (property "Val" "100k")
    (property "ki_description" "SMD Chip Resistor, 100 kohm, ± 1%, 62.5 mW, 0402 [1005 Metric], Thick Film, General Purpose")
    (property "ki_keywords" "0402, SMT, RESISTOR, PASSIVE")
    (attr smd)
    (fp_text reference "R34" (at 3.182 0.371 180) (layer "B.SilkS")
        (effects (font (size 0.7 0.7) (thickness 0.15)) (justify left bottom mirror))
    )
    (fp_text value "R_100k_0402" (at -1.011843 -1.772047 180) (layer "B.Fab")
        (effects (font (size 0.7 0.7) (thickness 0.15)) (justify left bottom mirror))
    )
    (fp_text user "${REFERENCE}" (at -0.95 -3.168 180) (layer "B.Fab") hide
        (effects (font (size 0.7 0.7) (thickness 0.15)) (justify left bottom mirror))
    )
    (fp_text user "Author: Antmicro" (at -0.95 -4.169 180) (layer "B.Fab") hide
        (effects (font (size 0.7 0.7) (thickness 0.15)) (justify left bottom mirror))
    )
    (fp_text user "License: Apache-2.0" (at -0.95 -5.169 180) (layer "B.Fab") hide
        (effects (font (size 0.7 0.7) (thickness 0.15)) (justify left bottom mirror))
    )
    (fp_rect (start -0.925 0.47) (end 0.925 -0.47)
      (stroke (width 0.05) (type default)) (fill none) (layer "B.CrtYd"))
    (fp_rect (start -0.5 0.25) (end 0.5 -0.25)
      (stroke (width 0.15) (type solid)) (fill none) (layer "B.Fab"))
    (pad "1" smd roundrect (at -0.48 0) (size 0.59 0.64) (layers "B.Cu" "B.Paste" "B.Mask") (roundrect_rratio 0.25)
      (net 167 "Net-(U3-BUSPOWERZ(GPIO10))") (pintype "passive"))
    (pad "2" smd roundrect (at 0.48 0) (size 0.59 0.64) (layers "B.Cu" "B.Paste" "B.Mask") (roundrect_rratio 0.25)
      (net 9 "/Power/TPS_3V3") (pintype "passive"))
  )
	(footprint "antmicro-footprints:C_0402_1005Metric" (layer "B.Cu")
    (at 116.920001 61.195)
    (descr "Capacitor SMD 0402")
    (tags "capacitor SMD 0402")
    (property "Author" "Antmicro")
    (property "Dielectric" "")
    (property "License" "Apache-2.0")
    (property "MPN" "04025A330FAT2A")
    (property "Manufacturer" "KYOCERA AVX")
    (property "Sheetfile" "power.kicad_sch")
    (property "Sheetname" "Power")
    (property "Val" "33p")
    (property "Voltage" "")
    (property "ki_description" "SMD Multilayer Ceramic Capacitor, 33 pF, 50 V, 0402 [1005 Metric], ± 5%, C0G / NP0, MC")
    (property "ki_keywords" "0402, SMT, CAPACITOR, PASSIVE")
    (attr smd)
    (fp_text reference "C33" (at 3.094999 0.4 180) (layer "B.SilkS")
        (effects (font (size 0.7 0.7) (thickness 0.15)) (justify left bottom mirror))
    )
    (fp_text value "C_33p_0402" (at -1.022927 -2.155213 180) (layer "B.Fab")
        (effects (font (size 0.7 0.7) (thickness 0.15)) (justify left bottom mirror))
    )
    (fp_text user "Author: Antmicro" (at -0.939 -3.399 180) (layer "B.Fab") hide
        (effects (font (size 0.7 0.7) (thickness 0.15)) (justify left bottom mirror))
    )
    (fp_text user "License: Apache-2.0" (at -0.939 -5.799 180) (layer "B.Fab") hide
        (effects (font (size 0.7 0.7) (thickness 0.15)) (justify left bottom mirror))
    )
    (fp_text user "${REFERENCE}" (at -0.939 -4.599 180) (layer "B.Fab") hide
        (effects (font (size 0.7 0.7) (thickness 0.15)) (justify left bottom mirror))
    )
    (fp_rect (start -0.925 0.47) (end 0.925 -0.47)
      (stroke (width 0.05) (type default)) (fill none) (layer "B.CrtYd"))
    (fp_line (start -0.494 -0.248) (end -0.494 0.25)
      (stroke (width 0.15) (type solid)) (layer "B.Fab"))
    (fp_line (start -0.494 0.25) (end 0.504 0.25)
      (stroke (width 0.15) (type solid)) (layer "B.Fab"))
    (fp_line (start 0.504 -0.248) (end -0.494 -0.248)
      (stroke (width 0.15) (type solid)) (layer "B.Fab"))
    (fp_line (start 0.504 0.25) (end 0.504 -0.248)
      (stroke (width 0.15) (type solid)) (layer "B.Fab"))
    (pad "1" smd roundrect (at -0.48 0) (size 0.59 0.64) (layers "B.Cu" "B.Paste" "B.Mask") (roundrect_rratio 0.25)
      (net 99 "Net-(U2-FB)") (pintype "passive"))
    (pad "2" smd roundrect (at 0.48 0) (size 0.59 0.64) (layers "B.Cu" "B.Paste" "B.Mask") (roundrect_rratio 0.25)
      (net 100 "Net-(D2-A)") (pintype "passive"))
  )
	(footprint "antmicro-footprints:C_0402_1005Metric" (layer "B.Cu")
    (at 142.15 74.482 -90)
    (descr "Capacitor SMD 0402")
    (tags "capacitor SMD 0402")
    (property "Author" "Antmicro")
    (property "Dielectric" "X5R")
    (property "License" "Apache-2.0")
    (property "MPN" "GRM155R61H104KE14D")
    (property "Manufacturer" "Murata")
    (property "Sheetfile" "tb-power.kicad_sch")
    (property "Sheetname" "Thunderbolt Controller - Power")
    (property "Val" "100n")
    (property "Voltage" "50V")
    (property "ki_description" "SMD Multilayer Ceramic Capacitor, 0.1 µF, 50 V, 0402 [1005 Metric], ± 10%, X5R, GRM Series")
    (property "ki_keywords" "0402, SMT, CAPACITOR, PASSIVE, CERAMIC, MLCC")
    (attr smd)
    (fp_text reference "C93" (at -5.521 -1.487 90) (layer "B.SilkS")
        (effects (font (size 0.7 0.7) (thickness 0.15)) (justify left bottom mirror))
    )
    (fp_text value "C_100n_0402" (at -1.022927 -2.155213 90) (layer "B.Fab")
        (effects (font (size 0.7 0.7) (thickness 0.15)) (justify left bottom mirror))
    )
    (fp_text user "Author: Antmicro" (at -0.939 -3.399 90) (layer "B.Fab") hide
        (effects (font (size 0.7 0.7) (thickness 0.15)) (justify left bottom mirror))
    )
    (fp_text user "${REFERENCE}" (at -0.939 -4.599 90) (layer "B.Fab") hide
        (effects (font (size 0.7 0.7) (thickness 0.15)) (justify left bottom mirror))
    )
    (fp_text user "License: Apache-2.0" (at -0.939 -5.799 90) (layer "B.Fab") hide
        (effects (font (size 0.7 0.7) (thickness 0.15)) (justify left bottom mirror))
    )
    (fp_rect (start -0.925 0.47) (end 0.925 -0.47)
      (stroke (width 0.05) (type default)) (fill none) (layer "B.CrtYd"))
    (fp_line (start -0.494 -0.248) (end -0.494 0.25)
      (stroke (width 0.15) (type solid)) (layer "B.Fab"))
    (fp_line (start -0.494 0.25) (end 0.504 0.25)
      (stroke (width 0.15) (type solid)) (layer "B.Fab"))
    (fp_line (start 0.504 -0.248) (end -0.494 -0.248)
      (stroke (width 0.15) (type solid)) (layer "B.Fab"))
    (fp_line (start 0.504 0.25) (end 0.504 -0.248)
      (stroke (width 0.15) (type solid)) (layer "B.Fab"))
    (pad "1" smd roundrect (at -0.48 0 270) (size 0.59 0.64) (layers "B.Cu" "B.Paste" "B.Mask") (roundrect_rratio 0.25)
      (net 1 "GND") (pintype "passive"))
    (pad "2" smd roundrect (at 0.48 0 270) (size 0.59 0.64) (layers "B.Cu" "B.Paste" "B.Mask") (roundrect_rratio 0.25)
      (net 2 "3V3_SYS") (pintype "passive"))
  )
	(footprint "antmicro-footprints:R_0402_1005Metric" (layer "B.Cu")
    (at 136.2 70.72 90)
    (descr "Resistor SMD 0402")
    (tags "resistor SMD 0402")
    (property "Author" "Antmicro")
    (property "License" "Apache-2.0")
    (property "MPN" "CR0402-FX-1003GLF")
    (property "Manufacturer" "Bourns")
    (property "Sheetfile" "tb.kicad_sch")
    (property "Sheetname" "TB Controller")
    (property "Tolerance" "1%")
    (property "Val" "100k")
    (property "ki_description" "SMD Chip Resistor, 100 kohm, ± 1%, 62.5 mW, 0402 [1005 Metric], Thick Film, General Purpose")
    (property "ki_keywords" "0402, SMT, RESISTOR, PASSIVE")
    (attr smd)
    (fp_text reference "R90" (at -1.035 0.434 270) (layer "B.SilkS")
        (effects (font (size 0.7 0.7) (thickness 0.15)) (justify left bottom mirror))
    )
    (fp_text value "R_100k_0402" (at -1.011843 -1.772047 270) (layer "B.Fab")
        (effects (font (size 0.7 0.7) (thickness 0.15)) (justify left bottom mirror))
    )
    (fp_text user "Author: Antmicro" (at -0.95 -4.169 270) (layer "B.Fab") hide
        (effects (font (size 0.7 0.7) (thickness 0.15)) (justify left bottom mirror))
    )
    (fp_text user "${REFERENCE}" (at -0.95 -3.168 270) (layer "B.Fab") hide
        (effects (font (size 0.7 0.7) (thickness 0.15)) (justify left bottom mirror))
    )
    (fp_text user "License: Apache-2.0" (at -0.95 -5.169 270) (layer "B.Fab") hide
        (effects (font (size 0.7 0.7) (thickness 0.15)) (justify left bottom mirror))
    )
    (fp_rect (start -0.925 0.47) (end 0.925 -0.47)
      (stroke (width 0.05) (type default)) (fill none) (layer "B.CrtYd"))
    (fp_rect (start -0.5 0.25) (end 0.5 -0.25)
      (stroke (width 0.15) (type solid)) (fill none) (layer "B.Fab"))
    (pad "1" smd roundrect (at -0.48 0 90) (size 0.59 0.64) (layers "B.Cu" "B.Paste" "B.Mask") (roundrect_rratio 0.25)
      (net 54 "PCIE_WAKE") (pintype "passive"))
    (pad "2" smd roundrect (at 0.48 0 90) (size 0.59 0.64) (layers "B.Cu" "B.Paste" "B.Mask") (roundrect_rratio 0.25)
      (net 2 "3V3_SYS") (pintype "passive"))
  )
	(footprint "antmicro-footprints:R_0402_1005Metric" (layer "B.Cu")
    (at 138.25 66.82 90)
    (descr "Resistor SMD 0402")
    (tags "resistor SMD 0402")
    (property "Author" "Antmicro")
    (property "License" "Apache-2.0")
    (property "MPN" "CR0402-FX-1402GLF")
    (property "Manufacturer" "Bourns")
    (property "Sheetfile" "tb.kicad_sch")
    (property "Sheetname" "TB Controller")
    (property "Tolerance" "1%")
    (property "Val" "14k")
    (property "dnp" "")
    (property "ki_description" "SMD Chip Resistor, 14 kohm, ± 1%, 100 mW, 0402 [1005 Metric], Thick Film, Precision")
    (property "ki_keywords" "0402, SMT, RESISTOR, PASSIVE")
    (attr smd)
    (fp_text reference "R76" (at 3.066 0.434 270) (layer "B.SilkS")
        (effects (font (size 0.7 0.7) (thickness 0.15)) (justify left bottom mirror))
    )
    (fp_text value "R_14k_0402" (at -1.011843 -1.772047 270) (layer "B.Fab")
        (effects (font (size 0.7 0.7) (thickness 0.15)) (justify left bottom mirror))
    )
    (fp_text user "Author: Antmicro" (at -0.95 -4.169 270) (layer "B.Fab") hide
        (effects (font (size 0.7 0.7) (thickness 0.15)) (justify left bottom mirror))
    )
    (fp_text user "License: Apache-2.0" (at -0.95 -5.169 270) (layer "B.Fab") hide
        (effects (font (size 0.7 0.7) (thickness 0.15)) (justify left bottom mirror))
    )
    (fp_text user "${REFERENCE}" (at -0.95 -3.168 270) (layer "B.Fab") hide
        (effects (font (size 0.7 0.7) (thickness 0.15)) (justify left bottom mirror))
    )
    (fp_rect (start -0.925 0.47) (end 0.925 -0.47)
      (stroke (width 0.05) (type default)) (fill none) (layer "B.CrtYd"))
    (fp_rect (start -0.5 0.25) (end 0.5 -0.25)
      (stroke (width 0.15) (type solid)) (fill none) (layer "B.Fab"))
    (pad "1" smd roundrect (at -0.48 0 90) (size 0.59 0.64) (layers "B.Cu" "B.Paste" "B.Mask") (roundrect_rratio 0.25)
      (net 191 "Net-(U4C-DPSRC_RBIAS)") (pintype "passive"))
    (pad "2" smd roundrect (at 0.48 0 90) (size 0.59 0.64) (layers "B.Cu" "B.Paste" "B.Mask") (roundrect_rratio 0.25)
      (net 1 "GND") (pintype "passive"))
  )
	(footprint "antmicro-footprints:R_0402_1005Metric" (layer "B.Cu")
    (at 135.175 70.72 90)
    (descr "Resistor SMD 0402")
    (tags "resistor SMD 0402")
    (property "Author" "Antmicro")
    (property "License" "Apache-2.0")
    (property "MPN" "CR0402-FX-1003GLF")
    (property "Manufacturer" "Bourns")
    (property "Sheetfile" "tb.kicad_sch")
    (property "Sheetname" "TB Controller")
    (property "Tolerance" "1%")
    (property "Val" "100k")
    (property "ki_description" "SMD Chip Resistor, 100 kohm, ± 1%, 62.5 mW, 0402 [1005 Metric], Thick Film, General Purpose")
    (property "ki_keywords" "0402, SMT, RESISTOR, PASSIVE")
    (attr smd)
    (fp_text reference "R72" (at -1.035 0.434 270) (layer "B.SilkS")
        (effects (font (size 0.7 0.7) (thickness 0.15)) (justify left bottom mirror))
    )
    (fp_text value "R_100k_0402" (at -1.011843 -1.772047 270) (layer "B.Fab")
        (effects (font (size 0.7 0.7) (thickness 0.15)) (justify left bottom mirror))
    )
    (fp_text user "License: Apache-2.0" (at -0.95 -5.169 270) (layer "B.Fab") hide
        (effects (font (size 0.7 0.7) (thickness 0.15)) (justify left bottom mirror))
    )
    (fp_text user "${REFERENCE}" (at -0.95 -3.168 270) (layer "B.Fab") hide
        (effects (font (size 0.7 0.7) (thickness 0.15)) (justify left bottom mirror))
    )
    (fp_text user "Author: Antmicro" (at -0.95 -4.169 270) (layer "B.Fab") hide
        (effects (font (size 0.7 0.7) (thickness 0.15)) (justify left bottom mirror))
    )
    (fp_rect (start -0.925 0.47) (end 0.925 -0.47)
      (stroke (width 0.05) (type default)) (fill none) (layer "B.CrtYd"))
    (fp_rect (start -0.5 0.25) (end 0.5 -0.25)
      (stroke (width 0.15) (type solid)) (fill none) (layer "B.Fab"))
    (pad "1" smd roundrect (at -0.48 0 90) (size 0.59 0.64) (layers "B.Cu" "B.Paste" "B.Mask") (roundrect_rratio 0.25)
      (net 187 "Net-(U4E-PB_DPSRC_HPD)") (pintype "passive"))
    (pad "2" smd roundrect (at 0.48 0 90) (size 0.59 0.64) (layers "B.Cu" "B.Paste" "B.Mask") (roundrect_rratio 0.25)
      (net 1 "GND") (pintype "passive"))
  )
)
